# T6G (Grand Teton) — schematic netlist excerpt (pin names and nets, part order shuffled) for the footprints in the layout excerpt that follows; sources: Cadence DE-HDL packaged netlist, KiCad conversion of 04192023_DAF0TMB3IC0_F0TG_MB_C_brd_V02_OCP.brd

R57  Q_RES  0 5% CHIP  pkg 0402LF  page 81 : A = RST_CPU1_RESETL_N ; B = FM_RST_CPU1_RESETL_N

U66  74LVC1G126SE7  74LVC1G126SE-7 IC  pkg SOT353_0-65_2X1-25  page 132
  OE  = OCP_SFF_AUX_PWR_EN_R1
  A  = FM_OCP_SFF_PWR_GOOD
  GND  = GND
  Y  = FB_BMC_ISOLATE_R1
  VCC  = P3V3_AUX

(kicad_pcb
	(version 20260206)
	(generator "pcbnew")
	(generator_version "10.0")
	(general
		(thickness 1.6)
		(legacy_teardrops no)
	)
	(paper "A4")
	(title_block
		(title "04192023_DAF0TMB3IC0_F0TG_MB_C_brd_V02_OCP.brd")
		(comment 1 "Grand Teton / footprints 1146-1147 of 8354")
	)
	(layers
		(0 "F.Cu" signal "TOP")
		(4 "In1.Cu" signal "GND")
		(6 "In2.Cu" signal "IN1")
		(8 "In3.Cu" signal "GND1")
		(10 "In4.Cu" signal "IN2")
		(12 "In5.Cu" signal "GND2")
		(14 "In6.Cu" signal "IN3")
		(16 "In7.Cu" signal "GND3")
		(18 "In8.Cu" signal "VCC")
		(20 "In9.Cu" signal "VCC1")
		(22 "In10.Cu" signal "GND4")
		(24 "In11.Cu" signal "IN4")
		(26 "In12.Cu" signal "GND5")
		(28 "In13.Cu" signal "IN5")
		(30 "In14.Cu" signal "GND6")
		(32 "In15.Cu" signal "IN6")
		(34 "In16.Cu" signal "GND7")
		(2 "B.Cu" signal "BOTTOM")
		(9 "F.Adhes" user "F.Adhesive")
		(11 "B.Adhes" user "B.Adhesive")
		(13 "F.Paste" user "Package Geometry/Pastemask Top")
		(15 "B.Paste" user "Package Geometry/Pastemask Bottom")
		(5 "F.SilkS" user "Ref Des/Silkscreen Top")
		(7 "B.SilkS" user "Ref Des/Silkscreen Bottom")
		(1 "F.Mask" user "Board Geometry/Soldermask Top")
		(3 "B.Mask" user "Board Geometry/Soldermask Bottom")
		(17 "Dwgs.User" user "User.Drawings")
		(19 "Cmts.User" user "User.Comments")
		(21 "Eco1.User" user "User.Eco1")
		(23 "Eco2.User" user "User.Eco2")
		(25 "Edge.Cuts" user "Board Geometry/Outline")
		(27 "Margin" user)
		(31 "F.CrtYd" user "Package Geometry/Place Bound Top")
		(29 "B.CrtYd" user "Package Geometry/Place Bound Bottom")
		(35 "F.Fab" user "Ref Des/Assembly Top")
		(33 "B.Fab" user "Ref Des/Assembly Bottom")
	)
	(footprint ""
		(layer "F.Cu")
		(at 181.991 -129.377948 -90)
		(property "Reference" "R57"
			(at 0 0 270)
			(layer "F.SilkS")
			(hide yes)
			(effects
				(font
					(size 1.27 1.27)
				)
			)
		)
		(property "Value" ""
			(at 0 0 270)
			(layer "F.Fab")
			(effects
				(font
					(size 1.27 1.27)
				)
			)
		)
		(duplicate_pad_numbers_are_jumpers no)
		(fp_line
			(start -0.7874 0.4064)
			(end -0.7874 -0.4064)
			(stroke
				(width 0.1524)
				(type default)
			)
			(layer "F.SilkS")
		)
		(fp_line
			(start 0.7874 0.4064)
			(end -0.7874 0.4064)
			(stroke
				(width 0.1524)
				(type default)
			)
			(layer "F.SilkS")
		)
		(fp_line
			(start -0.7874 -0.4064)
			(end 0.7874 -0.4064)
			(stroke
				(width 0.1524)
				(type default)
			)
			(layer "F.SilkS")
		)
		(fp_line
			(start 0.7874 -0.4064)
			(end 0.7874 0.4064)
			(stroke
				(width 0.1524)
				(type default)
			)
			(layer "F.SilkS")
		)
		(fp_line
			(start -0.67945 0.3048)
			(end -0.67945 -0.305054)
			(stroke
				(width 0.1)
				(type default)
			)
			(layer "F.Fab")
		)
		(fp_line
			(start -0.12065 0.3048)
			(end -0.67945 0.3048)
			(stroke
				(width 0.1)
				(type default)
			)
			(layer "F.Fab")
		)
		(fp_line
			(start 0.120396 0.3048)
			(end 0.120396 0.2794)
			(stroke
				(width 0.1)
				(type default)
			)
			(layer "F.Fab")
		)
		(fp_line
			(start 0.67945 0.3048)
			(end 0.120396 0.3048)
			(stroke
				(width 0.1)
				(type default)
			)
			(layer "F.Fab")
		)
		(fp_line
			(start -0.12065 0.2794)
			(end -0.12065 0.3048)
			(stroke
				(width 0.1)
				(type default)
			)
			(layer "F.Fab")
		)
		(fp_line
			(start 0.120396 0.2794)
			(end -0.12065 0.2794)
			(stroke
				(width 0.1)
				(type default)
			)
			(layer "F.Fab")
		)
		(fp_line
			(start -0.12065 -0.2794)
			(end 0.12065 -0.2794)
			(stroke
				(width 0.1)
				(type default)
			)
			(layer "F.Fab")
		)
		(fp_line
			(start 0.12065 -0.2794)
			(end 0.12065 -0.3048)
			(stroke
				(width 0.1)
				(type default)
			)
			(layer "F.Fab")
		)
		(fp_line
			(start 0.12065 -0.3048)
			(end 0.67945 -0.3048)
			(stroke
				(width 0.1)
				(type default)
			)
			(layer "F.Fab")
		)
		(fp_line
			(start 0.67945 -0.3048)
			(end 0.67945 0.3048)
			(stroke
				(width 0.1)
				(type default)
			)
			(layer "F.Fab")
		)
		(fp_line
			(start -0.67945 -0.305054)
			(end -0.12065 -0.305054)
			(stroke
				(width 0.1)
				(type default)
			)
			(layer "F.Fab")
		)
		(fp_line
			(start -0.12065 -0.305054)
			(end -0.12065 -0.2794)
			(stroke
				(width 0.1)
				(type default)
			)
			(layer "F.Fab")
		)
		(pad "1" smd circle
			(at -0.40005 0 270)
			(size 0 0)
			(layers "F.Cu" "F.Mask" "F.Paste")
			(net "RST_CPU1_RESETL_N")
		)
		(pad "2" smd circle
			(at 0.40005 0 270)
			(size 0 0)
			(layers "F.Cu" "F.Mask" "F.Paste")
			(net "FM_RST_CPU1_RESETL_N")
		)
	)
	(footprint ""
		(layer "F.Cu")
		(at 459.579726 -98.514408)
		(property "Reference" "U66"
			(at -4.11226 -1.882648 0)
			(unlocked yes)
			(layer "F.SilkS")
			(effects
				(font
					(size 0.7874 0.5842)
					(thickness 0.1524)
				)
				(justify left)
			)
		)
		(property "Value" ""
			(at 0 0 0)
			(layer "F.Fab")
			(effects
				(font
					(size 1.27 1.27)
				)
			)
		)
		(duplicate_pad_numbers_are_jumpers no)
		(fp_line
			(start -1.400048 1.100074)
			(end -1.400048 -1.100074)
			(stroke
				(width 0.1524)
				(type default)
			)
			(layer "F.SilkS")
		)
		(fp_line
			(start 1.400048 -1.100074)
			(end -1.400048 -1.100074)
			(stroke
				(width 0.1524)
				(type default)
			)
			(layer "F.SilkS")
		)
		(fp_line
			(start 1.400048 -1.100074)
			(end 1.400048 1.100074)
			(stroke
				(width 0.1524)
				(type default)
			)
			(layer "F.SilkS")
		)
		(fp_line
			(start 1.400048 1.100074)
			(end -1.400048 1.100074)
			(stroke
				(width 0.1524)
				(type default)
			)
			(layer "F.SilkS")
		)
		(fp_poly
			(pts
				(xy -1.559052 -2.258314) (xy -0.543052 -2.258314) (xy -1.051052 -1.242314)
			)
			(stroke
				(width 0)
				(type default)
			)
			(fill yes)
			(layer "F.SilkS")
		)
		(fp_line
			(start -0.674878 -1.100074)
			(end 0.674878 -1.100074)
			(stroke
				(width 0.1)
				(type default)
			)
			(layer "F.Fab")
		)
		(fp_line
			(start -0.674878 1.100074)
			(end -0.674878 -1.100074)
			(stroke
				(width 0.1)
				(type default)
			)
			(layer "F.Fab")
		)
		(fp_line
			(start 0.674878 -1.100074)
			(end 0.674878 1.100074)
			(stroke
				(width 0.1)
				(type default)
			)
			(layer "F.Fab")
		)
		(fp_line
			(start 0.674878 1.100074)
			(end -0.674878 1.100074)
			(stroke
				(width 0.1)
				(type default)
			)
			(layer "F.Fab")
		)
		(fp_poly
			(pts
				(xy -1.590548 -0.649986) (xy -2.606548 -1.157986) (xy -2.606548 -0.141986)
			)
			(stroke
				(width 0)
				(type default)
			)
			(fill yes)
			(layer "F.Fab")
		)
		(pad "1" smd rect
			(at -0.94996 -0.649986 270)
			(size 0.4318 0.6096)
			(layers "F.Cu" "F.Mask" "F.Paste")
			(net "OCP_SFF_AUX_PWR_EN_R1")
		)
		(pad "2" smd rect
			(at -0.94996 0 270)
			(size 0.4318 0.6096)
			(layers "F.Cu" "F.Mask" "F.Paste")
			(net "FM_OCP_SFF_PWR_GOOD")
		)
		(pad "3" smd rect
			(at -0.94996 0.649986 270)
			(size 0.4318 0.6096)
			(layers "F.Cu" "F.Mask" "F.Paste")
			(net "GND")
		)
		(pad "4" smd rect
			(at 0.94996 0.649986 270)
			(size 0.4318 0.6096)
			(layers "F.Cu" "F.Mask" "F.Paste")
			(net "FB_BMC_ISOLATE_R1")
		)
		(pad "5" smd rect
			(at 0.94996 -0.649986 270)
			(size 0.4318 0.6096)
			(layers "F.Cu" "F.Mask" "F.Paste")
			(net "P3V3_AUX")
		)
	)
)
